FILE_TYPE = CONNECTIVITY;
{Allegro Design Entry HDL 17.4-2019 S026 (4007227) 1/17/2022}
"PAGE_NUMBER" = 42;
0"NC";
1"M_F_CPU1_SA_DQ<31:0>";
2"M_F_CPU1_SB_DQ<31:0>";
3"M_F_CPU1_SA_CB<7:0>";
4"M_F_CPU1_SB_CB<7:0>";
5"M_F_CPU1_SA_DQS_DP<9:0>";
6"M_F_CPU1_SA_DQS_DN<9:0>";
7"M_F_CPU1_SB_DQS_DN<9:0>";
8"M_F_CPU1_SB_DQS_DP<9:0>";
9"M_F_CPU1_SA_CA<6:0>";
10"M_F_CPU1_SB_CA<6:0>";
11"M_F_CPU1_ALERT_N";
12"M_F_CPU1_ALERT_R_N";
13"TP_M_F_CPU1_SA_TEST39F";
14"M_F_CPU1_CLK_DP<0>";
15"M_F_CPU1_CLK_DN<0>";
16"M_F_CPU1_SA_CS_N<0>";
17"M_F_CPU1_SA_CS_N<1>";
18"M_F_CPU1_SA_RSP<0>";
19"M_F_CPU1_SA_PAR";
20"M_F_CPU1_SB_CS_N<0>";
21"M_F_CPU1_SB_CS_N<1>";
22"M_F_CPU1_SB_RSP<0>";
23"M_F_CPU1_SB_PAR";
24"M_F_CPU1_RESET_N";
25"M_F_CPU1_SB_CA<6>";
26"M_F_CPU1_SA_CA<6>";
27"M_F_CPU1_SB_CA<5>";
28"M_F_CPU1_SA_CA<5>";
29"M_F_CPU1_SB_CA<4>";
30"M_F_CPU1_SA_CA<4>";
31"M_F_CPU1_SB_CA<3>";
32"M_F_CPU1_SA_CA<3>";
33"M_F_CPU1_SB_CA<2>";
34"M_F_CPU1_SA_CA<2>";
35"M_F_CPU1_SB_CA<1>";
36"M_F_CPU1_SA_CA<1>";
37"M_F_CPU1_SB_CA<0>";
38"M_F_CPU1_SA_CA<0>";
39"M_F_CPU1_SB_DQS_DP<9>";
40"M_F_CPU1_SB_DQS_DP<1>";
41"M_F_CPU1_SB_DQS_DN<5>";
42"M_F_CPU1_SB_DQS_DP<0>";
43"M_F_CPU1_SB_DQS_DN<4>";
44"M_F_CPU1_SB_DQS_DN<3>";
45"M_F_CPU1_SB_DQS_DN<2>";
46"M_F_CPU1_SB_DQS_DN<1>";
47"M_F_CPU1_SB_DQS_DN<0>";
48"M_F_CPU1_SB_DQS_DP<8>";
49"M_F_CPU1_SB_DQS_DP<7>";
50"M_F_CPU1_SB_DQS_DP<6>";
51"M_F_CPU1_SB_DQS_DP<5>";
52"M_F_CPU1_SB_DQS_DN<9>";
53"M_F_CPU1_SB_DQS_DP<4>";
54"M_F_CPU1_SB_DQS_DN<8>";
55"M_F_CPU1_SB_DQS_DP<3>";
56"M_F_CPU1_SB_DQS_DN<7>";
57"M_F_CPU1_SB_DQS_DP<2>";
58"M_F_CPU1_SB_DQS_DN<6>";
59"M_F_CPU1_SA_DQS_DP<7>";
60"M_F_CPU1_SA_DQS_DP<6>";
61"M_F_CPU1_SA_DQS_DP<5>";
62"M_F_CPU1_SA_DQS_DN<9>";
63"M_F_CPU1_SA_DQS_DP<4>";
64"M_F_CPU1_SA_DQS_DN<8>";
65"M_F_CPU1_SA_DQS_DP<3>";
66"M_F_CPU1_SA_DQS_DN<7>";
67"M_F_CPU1_SA_DQS_DP<2>";
68"M_F_CPU1_SA_DQS_DN<6>";
69"M_F_CPU1_SA_DQS_DP<1>";
70"M_F_CPU1_SA_DQS_DN<5>";
71"M_F_CPU1_SA_DQS_DN<4>";
72"M_F_CPU1_SA_DQS_DN<3>";
73"M_F_CPU1_SA_DQS_DN<2>";
74"M_F_CPU1_SA_DQS_DN<1>";
75"M_F_CPU1_SA_DQS_DN<0>";
76"M_F_CPU1_SA_DQS_DP<9>";
77"M_F_CPU1_SA_DQS_DP<8>";
78"M_F_CPU1_SA_DQS_DP<0>";
79"M_F_CPU1_SB_CB<7>";
80"M_F_CPU1_SB_CB<6>";
81"M_F_CPU1_SB_CB<5>";
82"M_F_CPU1_SB_CB<4>";
83"M_F_CPU1_SB_CB<3>";
84"M_F_CPU1_SB_CB<2>";
85"M_F_CPU1_SB_DQ<29>";
86"M_F_CPU1_SB_DQ<28>";
87"M_F_CPU1_SB_DQ<27>";
88"M_F_CPU1_SB_DQ<26>";
89"M_F_CPU1_SB_DQ<25>";
90"M_F_CPU1_SB_DQ<24>";
91"M_F_CPU1_SA_CB<7>";
92"M_F_CPU1_SB_CB<1>";
93"M_F_CPU1_SA_CB<6>";
94"M_F_CPU1_SB_CB<0>";
95"M_F_CPU1_SB_DQ<31>";
96"M_F_CPU1_SA_CB<5>";
97"M_F_CPU1_SB_DQ<30>";
98"M_F_CPU1_SA_CB<4>";
99"M_F_CPU1_SA_CB<3>";
100"M_F_CPU1_SA_CB<2>";
101"M_F_CPU1_SA_CB<1>";
102"M_F_CPU1_SA_CB<0>";
103"M_F_CPU1_SB_DQ<6>";
104"M_F_CPU1_SB_DQ<18>";
105"M_F_CPU1_SB_DQ<17>";
106"M_F_CPU1_SB_DQ<16>";
107"M_F_CPU1_SB_DQ<15>";
108"M_F_CPU1_SB_DQ<14>";
109"M_F_CPU1_SB_DQ<13>";
110"M_F_CPU1_SB_DQ<12>";
111"M_F_CPU1_SB_DQ<23>";
112"M_F_CPU1_SB_DQ<11>";
113"M_F_CPU1_SB_DQ<22>";
114"M_F_CPU1_SB_DQ<10>";
115"M_F_CPU1_SB_DQ<21>";
116"M_F_CPU1_SB_DQ<20>";
117"M_F_CPU1_SB_DQ<9>";
118"M_F_CPU1_SB_DQ<8>";
119"M_F_CPU1_SB_DQ<7>";
120"M_F_CPU1_SB_DQ<19>";
121"M_F_CPU1_SB_DQ<5>";
122"M_F_CPU1_SB_DQ<4>";
123"M_F_CPU1_SB_DQ<3>";
124"M_F_CPU1_SB_DQ<2>";
125"M_F_CPU1_SA_DQ<19>";
126"M_F_CPU1_SB_DQ<1>";
127"M_F_CPU1_SA_DQ<29>";
128"M_F_CPU1_SB_DQ<0>";
129"M_F_CPU1_SA_DQ<28>";
130"M_F_CPU1_SA_DQ<27>";
131"M_F_CPU1_SA_DQ<26>";
132"M_F_CPU1_SA_DQ<25>";
133"M_F_CPU1_SA_DQ<24>";
134"M_F_CPU1_SA_DQ<23>";
135"M_F_CPU1_SA_DQ<22>";
136"M_F_CPU1_SA_DQ<21>";
137"M_F_CPU1_SA_DQ<20>";
138"M_F_CPU1_SA_DQ<31>";
139"M_F_CPU1_SA_DQ<30>";
140"M_F_CPU1_SA_DQ<7>";
141"M_F_CPU1_SA_DQ<6>";
142"M_F_CPU1_SA_DQ<5>";
143"M_F_CPU1_SA_DQ<4>";
144"M_F_CPU1_SA_DQ<3>";
145"M_F_CPU1_SA_DQ<2>";
146"M_F_CPU1_SA_DQ<1>";
147"M_F_CPU1_SA_DQ<18>";
148"M_F_CPU1_SA_DQ<17>";
149"M_F_CPU1_SA_DQ<16>";
150"M_F_CPU1_SA_DQ<15>";
151"M_F_CPU1_SA_DQ<14>";
152"M_F_CPU1_SA_DQ<13>";
153"M_F_CPU1_SA_DQ<12>";
154"M_F_CPU1_SA_DQ<11>";
155"M_F_CPU1_SA_DQ<10>";
156"M_F_CPU1_SA_DQ<9>";
157"M_F_CPU1_SA_DQ<8>";
158"M_F_CPU1_SA_DQ<0>";
%"GENOA_SP5"
"6","(-4600,3775)","0","pure_quanta","I159";
;
LOCATION"U26"
$SEC"6"
CDS_SEC"6"
PART_TYPE"SMLF"
MATERIAL"IO"
VALUE"SOCKET6096_13568-001"
CDS_LIB"pure_quanta"
CDS_LMAN_SYM_OUTLINE"-650,2525,650,-2525"
NEEDS_NO_SIZE"TRUE"
PART_NUMBER"DGA^6000030";
"TEST39F"
$PN"BF65"13;
"MF1_CLK_L"
$PN"BG67"0;
"MF1_CLK_H"
$PN"BF67"0;
"MF0_CLK_L"
$PN"BD67"15;
"MF0_CLK_H"
$PN"BC67"14;
"MFB_DQS_H9"
$PN"BV67"39;
"MFB_PAR"
$PN"BL67"23;
"MFA_PAR"
$PN"BC66"19;
"MFA0_CS_L0"
$PN"AV67"16;
"MFA_DATA7"
$PN"L66"140;
"MFA_DQS_H7"
$PN"AA66"59;
"MFB_DATA6"
$PN"CG67"103;
"MFB_DATA18"
$PN"CR67"104;
"MFB_DATA29"
$PN"DE66"85;
"MFB_DQS_H1"
$PN"CK67"40;
"MFB_DQS_L5"
$PN"CE66"41;
"MFA_DATA6"
$PN"K67"141;
"MFA_DQS_H6"
$PN"R66"60;
"MFB1_RSP_L"
$PN"BR67"0;
"MFB_DATA5"
$PN"CG66"121;
"MFB_DATA17"
$PN"CR66"105;
"MFB_DATA28"
$PN"DD67"86;
"MFB_DQS_H0"
$PN"CD67"42;
"MFB_DQS_L4"
$PN"BW66"43;
"MFA_DATA5"
$PN"K65"142;
"MFA_DQS_H5"
$PN"J66"61;
"MFA_DQS_L9"
$PN"AM65"62;
"MFB0_RSP_L"
$PN"BP67"22;
"MFB_CHECK7"
$PN"BV65"79;
"MFB_DATA4"
$PN"CF67"122;
"MFB_DATA16"
$PN"CP67"106;
"MFB_DATA27"
$PN"DB65"87;
"MFB_DQS_L3"
$PN"DC67"44;
"MFA_DATA4"
$PN"J67"143;
"MFA_DQS_H4"
$PN"AL67"63;
"MFA_DQS_L8"
$PN"AF65"64;
"MFB_CHECK6"
$PN"BU67"80;
"MFB_DATA3"
$PN"CD65"123;
"MFB_DATA15"
$PN"CP65"107;
"MFB_DATA26"
$PN"DA67"88;
"MFB_DQS_L2"
$PN"CU67"45;
"MFA_DATA3"
$PN"G66"144;
"MFA_DQS_H3"
$PN"AE67"65;
"MFA_DQS_L7"
$PN"Y65"66;
"MFB_CHECK5"
$PN"BU66"81;
"MFB_DATA2"
$PN"CC67"124;
"MFB_DATA14"
$PN"CN67"108;
"MFB_DATA25"
$PN"DA66"89;
"MFB_DQS_L1"
$PN"CL67"46;
"MFA_DATA2"
$PN"F67"145;
"MFA_DATA19"
$PN"W66"125;
"MFA_DQS_H2"
$PN"W67"67;
"MFA_DQS_L6"
$PN"P65"68;
"MFB_CA6"
$PN"BK67"25;
"MFB_CHECK4"
$PN"BT67"82;
"MFB_DATA1"
$PN"CC66"126;
"MFB_DATA13"
$PN"CN66"109;
"MFB_DATA24"
$PN"CY67"90;
"MFB_DQS_L0"
$PN"CE67"47;
"MFA_CA6"
$PN"BB65"26;
"MFA_DATA1"
$PN"F65"146;
"MFA_DATA18"
$PN"V67"147;
"MFA_DATA29"
$PN"AH65"127;
"MFA_DQS_H1"
$PN"N67"69;
"MFA_DQS_L5"
$PN"H65"70;
"MFB_CA5"
$PN"BK65"27;
"MFB_CHECK3"
$PN"CB65"83;
"MFB_DATA0"
$PN"CB67"128;
"MFB_DATA12"
$PN"CM67"110;
"MFB_DATA23"
$PN"CY65"111;
"MFA1_RSP_L"
$PN"BP65"0;
"MFA_CA5"
$PN"BB67"28;
"MFA_DATA0"
$PN"E67"158;
"MFA_DATA17"
$PN"V65"148;
"MFA_DATA28"
$PN"AG67"129;
"MFA_DQS_H0"
$PN"G67"78;
"MFA_DQS_L4"
$PN"AM67"71;
"MFB_CA4"
$PN"BJ66"29;
"MFB_CHECK2"
$PN"CA67"84;
"MFB_DATA11"
$PN"CK65"112;
"MFB_DATA22"
$PN"CW67"113;
"MFA0_RSP_L"
$PN"BN66"18;
"MFA_CA4"
$PN"BA67"30;
"MFA_CHECK7"
$PN"AR66"91;
"MFA_DATA16"
$PN"U67"149;
"MFA_DATA27"
$PN"AE66"130;
"MFA_DQS_L3"
$PN"AF67"72;
"MFB_CA3"
$PN"BJ67"31;
"MFB_CHECK1"
$PN"CA66"92;
"MFB_DATA10"
$PN"CJ67"114;
"MFB_DATA21"
$PN"CW66"115;
"MFA_CA3"
$PN"BA66"32;
"MFA_CHECK6"
$PN"AP67"93;
"MFA_DATA15"
$PN"U66"150;
"MFA_DATA26"
$PN"AD67"131;
"MFA_DQS_L2"
$PN"Y67"73;
"MFB1_CS_L1"
$PN"BM67"0;
"MFB_CA2"
$PN"BH67"33;
"MFB_CHECK0"
$PN"BY67"94;
"MFB_DATA20"
$PN"CV67"116;
"MFB_DATA31"
$PN"DF67"95;
"MFA_CA2"
$PN"AY65"34;
"MFA_CHECK5"
$PN"AP65"96;
"MFA_DATA14"
$PN"T67"151;
"MFA_DATA25"
$PN"AD65"132;
"MFA_DQS_L1"
$PN"P67"74;
"MFB0_CS_L1"
$PN"BN67"21;
"MFB1_CS_L0"
$PN"BL66"0;
"MFB_CA1"
$PN"BH65"35;
"MFB_DATA30"
$PN"DE67"97;
"MFB_DQS_H8"
$PN"DD65"48;
"MFA_CA1"
$PN"AY67"36;
"MFA_CHECK4"
$PN"AN67"98;
"MFA_DATA13"
$PN"T65"152;
"MFA_DATA24"
$PN"AC67"133;
"MFA_DQS_L0"
$PN"H67"75;
"MFB0_CS_L0"
$PN"BM65"20;
"MFB_CA0"
$PN"BG66"37;
"MFB_DQS_H7"
$PN"CV65"49;
"MFA_CA0"
$PN"AW67"38;
"MFA_CHECK3"
$PN"AL66"99;
"MFA_DATA12"
$PN"R67"153;
"MFA_DATA23"
$PN"AC66"134;
"MFB_DQS_H6"
$PN"CM65"50;
"MFA_CHECK2"
$PN"AK67"100;
"MFA_DATA11"
$PN"N66"154;
"MFA_DATA22"
$PN"AB67"135;
"MFB_DQS_H5"
$PN"CF65"51;
"MFB_DQS_L9"
$PN"BW67"52;
"MFA_CHECK1"
$PN"AK65"101;
"MFA_DATA10"
$PN"M67"155;
"MFA_DATA21"
$PN"AB65"136;
"MFB_DATA9"
$PN"CJ66"117;
"MFB_DQS_H4"
$PN"BY65"53;
"MFB_DQS_L8"
$PN"DC66"54;
"MFA1_CS_L1"
$PN"AV65"0;
"MFA_CHECK0"
$PN"AJ67"102;
"MFA_DATA9"
$PN"M65"156;
"MFA_DATA20"
$PN"AA67"137;
"MFA_DATA31"
$PN"AJ66"138;
"MFA_DQS_H9"
$PN"AN66"76;
"MFB_DATA8"
$PN"CH67"118;
"MFB_DQS_H3"
$PN"DB67"55;
"MFB_DQS_L7"
$PN"CU66"56;
"MFA0_CS_L1"
$PN"AW66"17;
"MFA1_CS_L0"
$PN"AU67"0;
"MFA_DATA8"
$PN"L67"157;
"MFA_DATA30"
$PN"AH67"139;
"MFA_DQS_H8"
$PN"AG66"77;
"MFB_DATA7"
$PN"CH65"119;
"MFB_DATA19"
$PN"CT65"120;
"MFB_DQS_H2"
$PN"CT67"57;
"MFB_DQS_L6"
$PN"CL66"58;
"MF_RESET_L"
$PN"AU66"24;
"MF_ALERT_L"
$PN"AT65"12;
%"TAP"
"1","(-3325,6150)","0","mstr_standard","I160";
;
CDS_LIB"mstr_standard"
BODY_TYPE"PLUMBING"
HDL_TAP"TRUE";
"B \NAC \NWC"1;
"S \NAC"
BN"0"158;
%"TAP"
"1","(-3325,6100)","0","mstr_standard","I163";
;
CDS_LIB"mstr_standard"
BODY_TYPE"PLUMBING"
HDL_TAP"TRUE";
"B \NAC \NWC"1;
"S \NAC"
BN"1"146;
%"TAP"
"1","(-3325,6050)","0","mstr_standard","I164";
;
CDS_LIB"mstr_standard"
BODY_TYPE"PLUMBING"
HDL_TAP"TRUE";
"B \NAC \NWC"1;
"S \NAC"
BN"2"145;
%"TAP"
"1","(-3325,5900)","0","mstr_standard","I165";
;
CDS_LIB"mstr_standard"
BODY_TYPE"PLUMBING"
HDL_TAP"TRUE";
"B \NAC \NWC"1;
"S \NAC"
BN"5"142;
%"TAP"
"1","(-3325,6000)","0","mstr_standard","I166";
;
CDS_LIB"mstr_standard"
BODY_TYPE"PLUMBING"
HDL_TAP"TRUE";
"B \NAC \NWC"1;
"S \NAC"
BN"3"144;
%"TAP"
"1","(-3325,5950)","0","mstr_standard","I167";
;
CDS_LIB"mstr_standard"
BODY_TYPE"PLUMBING"
HDL_TAP"TRUE";
"B \NAC \NWC"1;
"S \NAC"
BN"4"143;
%"TAP"
"1","(-3325,5850)","0","mstr_standard","I168";
;
CDS_LIB"mstr_standard"
BODY_TYPE"PLUMBING"
HDL_TAP"TRUE";
"B \NAC \NWC"1;
"S \NAC"
BN"6"141;
%"TAP"
"1","(-3325,5800)","0","mstr_standard","I169";
;
CDS_LIB"mstr_standard"
BODY_TYPE"PLUMBING"
HDL_TAP"TRUE";
"B \NAC \NWC"1;
"S \NAC"
BN"7"140;
%"TAP"
"1","(-3325,5700)","0","mstr_standard","I170";
;
CDS_LIB"mstr_standard"
BODY_TYPE"PLUMBING"
HDL_TAP"TRUE";
"B \NAC \NWC"1;
"S \NAC"
BN"8"157;
%"TAP"
"1","(-3325,5650)","0","mstr_standard","I171";
;
CDS_LIB"mstr_standard"
BODY_TYPE"PLUMBING"
HDL_TAP"TRUE";
"B \NAC \NWC"1;
"S \NAC"
BN"9"156;
%"TAP"
"1","(-3325,5550)","0","mstr_standard","I172";
;
CDS_LIB"mstr_standard"
BODY_TYPE"PLUMBING"
HDL_TAP"TRUE";
"B \NAC \NWC"1;
"S \NAC"
BN"11"154;
%"TAP"
"1","(-3325,5600)","0","mstr_standard","I173";
;
CDS_LIB"mstr_standard"
BODY_TYPE"PLUMBING"
HDL_TAP"TRUE";
"B \NAC \NWC"1;
"S \NAC"
BN"10"155;
%"TAP"
"1","(-3325,5450)","0","mstr_standard","I174";
;
CDS_LIB"mstr_standard"
BODY_TYPE"PLUMBING"
HDL_TAP"TRUE";
"B \NAC \NWC"1;
"S \NAC"
BN"13"152;
%"TAP"
"1","(-3325,5500)","0","mstr_standard","I175";
;
CDS_LIB"mstr_standard"
BODY_TYPE"PLUMBING"
HDL_TAP"TRUE";
"B \NAC \NWC"1;
"S \NAC"
BN"12"153;
%"TAP"
"1","(-3325,5400)","0","mstr_standard","I176";
;
CDS_LIB"mstr_standard"
BODY_TYPE"PLUMBING"
HDL_TAP"TRUE";
"B \NAC \NWC"1;
"S \NAC"
BN"14"151;
%"TAP"
"1","(-3325,5350)","0","mstr_standard","I177";
;
CDS_LIB"mstr_standard"
BODY_TYPE"PLUMBING"
HDL_TAP"TRUE";
"B \NAC \NWC"1;
"S \NAC"
BN"15"150;
%"TAP"
"1","(-3325,5250)","0","mstr_standard","I178";
;
CDS_LIB"mstr_standard"
BODY_TYPE"PLUMBING"
HDL_TAP"TRUE";
"B \NAC \NWC"1;
"S \NAC"
BN"16"149;
%"TAP"
"1","(-3325,5200)","0","mstr_standard","I179";
;
CDS_LIB"mstr_standard"
BODY_TYPE"PLUMBING"
HDL_TAP"TRUE";
"B \NAC \NWC"1;
"S \NAC"
BN"17"148;
%"TAP"
"1","(-3325,5150)","0","mstr_standard","I180";
;
CDS_LIB"mstr_standard"
BODY_TYPE"PLUMBING"
HDL_TAP"TRUE";
"B \NAC \NWC"1;
"S \NAC"
BN"18"147;
%"TAP"
"1","(-3325,5100)","0","mstr_standard","I181";
;
CDS_LIB"mstr_standard"
BODY_TYPE"PLUMBING"
HDL_TAP"TRUE";
"B \NAC \NWC"1;
"S \NAC"
BN"19"125;
%"TAP"
"1","(-3325,5050)","0","mstr_standard","I182";
;
CDS_LIB"mstr_standard"
BODY_TYPE"PLUMBING"
HDL_TAP"TRUE";
"B \NAC \NWC"1;
"S \NAC"
BN"20"137;
%"TAP"
"1","(-3325,5000)","0","mstr_standard","I183";
;
CDS_LIB"mstr_standard"
BODY_TYPE"PLUMBING"
HDL_TAP"TRUE";
"B \NAC \NWC"1;
"S \NAC"
BN"21"136;
%"TAP"
"1","(-3325,4900)","0","mstr_standard","I184";
;
CDS_LIB"mstr_standard"
BODY_TYPE"PLUMBING"
HDL_TAP"TRUE";
"B \NAC \NWC"1;
"S \NAC"
BN"23"134;
%"TAP"
"1","(-3325,4950)","0","mstr_standard","I185";
;
CDS_LIB"mstr_standard"
BODY_TYPE"PLUMBING"
HDL_TAP"TRUE";
"B \NAC \NWC"1;
"S \NAC"
BN"22"135;
%"TAP"
"1","(-3325,4750)","0","mstr_standard","I186";
;
CDS_LIB"mstr_standard"
BODY_TYPE"PLUMBING"
HDL_TAP"TRUE";
"B \NAC \NWC"1;
"S \NAC"
BN"25"132;
%"TAP"
"1","(-3325,4800)","0","mstr_standard","I187";
;
CDS_LIB"mstr_standard"
BODY_TYPE"PLUMBING"
HDL_TAP"TRUE";
"B \NAC \NWC"1;
"S \NAC"
BN"24"133;
%"TAP"
"1","(-3325,4700)","0","mstr_standard","I188";
;
CDS_LIB"mstr_standard"
BODY_TYPE"PLUMBING"
HDL_TAP"TRUE";
"B \NAC \NWC"1;
"S \NAC"
BN"26"131;
%"TAP"
"1","(-3325,4650)","0","mstr_standard","I189";
;
CDS_LIB"mstr_standard"
BODY_TYPE"PLUMBING"
HDL_TAP"TRUE";
"B \NAC \NWC"1;
"S \NAC"
BN"27"130;
%"TAP"
"1","(-3325,4600)","0","mstr_standard","I190";
;
CDS_LIB"mstr_standard"
BODY_TYPE"PLUMBING"
HDL_TAP"TRUE";
"B \NAC \NWC"1;
"S \NAC"
BN"28"129;
%"TAP"
"1","(-3325,4500)","0","mstr_standard","I191";
;
CDS_LIB"mstr_standard"
BODY_TYPE"PLUMBING"
HDL_TAP"TRUE";
"B \NAC \NWC"1;
"S \NAC"
BN"30"139;
%"TAP"
"1","(-3325,4550)","0","mstr_standard","I192";
;
CDS_LIB"mstr_standard"
BODY_TYPE"PLUMBING"
HDL_TAP"TRUE";
"B \NAC \NWC"1;
"S \NAC"
BN"29"127;
%"TAP"
"1","(-3325,4450)","0","mstr_standard","I193";
;
CDS_LIB"mstr_standard"
BODY_TYPE"PLUMBING"
HDL_TAP"TRUE";
"B \NAC \NWC"1;
"S \NAC"
BN"31"138;
%"TAP"
"1","(-3325,4350)","0","mstr_standard","I194";
;
CDS_LIB"mstr_standard"
BODY_TYPE"PLUMBING"
HDL_TAP"TRUE";
"B \NAC \NWC"2;
"S \NAC"
BN"0"128;
%"TAP"
"1","(-3325,4300)","0","mstr_standard","I195";
;
CDS_LIB"mstr_standard"
BODY_TYPE"PLUMBING"
HDL_TAP"TRUE";
"B \NAC \NWC"2;
"S \NAC"
BN"1"126;
%"TAP"
"1","(-3325,4250)","0","mstr_standard","I196";
;
CDS_LIB"mstr_standard"
BODY_TYPE"PLUMBING"
HDL_TAP"TRUE";
"B \NAC \NWC"2;
"S \NAC"
BN"2"124;
%"TAP"
"1","(-3325,4150)","0","mstr_standard","I197";
;
CDS_LIB"mstr_standard"
BODY_TYPE"PLUMBING"
HDL_TAP"TRUE";
"B \NAC \NWC"2;
"S \NAC"
BN"4"122;
%"TAP"
"1","(-3325,4200)","0","mstr_standard","I198";
;
CDS_LIB"mstr_standard"
BODY_TYPE"PLUMBING"
HDL_TAP"TRUE";
"B \NAC \NWC"2;
"S \NAC"
BN"3"123;
%"TAP"
"1","(-3325,4100)","0","mstr_standard","I199";
;
CDS_LIB"mstr_standard"
BODY_TYPE"PLUMBING"
HDL_TAP"TRUE";
"B \NAC \NWC"2;
"S \NAC"
BN"5"121;
%"TAP"
"1","(-3325,4000)","0","mstr_standard","I202";
;
CDS_LIB"mstr_standard"
BODY_TYPE"PLUMBING"
HDL_TAP"TRUE";
"B \NAC \NWC"2;
"S \NAC"
BN"7"119;
%"TAP"
"1","(-3325,4050)","0","mstr_standard","I203";
;
CDS_LIB"mstr_standard"
BODY_TYPE"PLUMBING"
HDL_TAP"TRUE";
"B \NAC \NWC"2;
"S \NAC"
BN"6"103;
%"TAP"
"1","(-3325,3850)","0","mstr_standard","I204";
;
CDS_LIB"mstr_standard"
BODY_TYPE"PLUMBING"
HDL_TAP"TRUE";
"B \NAC \NWC"2;
"S \NAC"
BN"9"117;
%"TAP"
"1","(-3325,3900)","0","mstr_standard","I205";
;
CDS_LIB"mstr_standard"
BODY_TYPE"PLUMBING"
HDL_TAP"TRUE";
"B \NAC \NWC"2;
"S \NAC"
BN"8"118;
%"TAP"
"1","(-3325,3800)","0","mstr_standard","I206";
;
CDS_LIB"mstr_standard"
BODY_TYPE"PLUMBING"
HDL_TAP"TRUE";
"B \NAC \NWC"2;
"S \NAC"
BN"10"114;
%"TAP"
"1","(-3325,3750)","0","mstr_standard","I207";
;
CDS_LIB"mstr_standard"
BODY_TYPE"PLUMBING"
HDL_TAP"TRUE";
"B \NAC \NWC"2;
"S \NAC"
BN"11"112;
%"TAP"
"1","(-3325,3600)","0","mstr_standard","I208";
;
CDS_LIB"mstr_standard"
BODY_TYPE"PLUMBING"
HDL_TAP"TRUE";
"B \NAC \NWC"2;
"S \NAC"
BN"14"108;
%"TAP"
"1","(-3325,3700)","0","mstr_standard","I209";
;
CDS_LIB"mstr_standard"
BODY_TYPE"PLUMBING"
HDL_TAP"TRUE";
"B \NAC \NWC"2;
"S \NAC"
BN"12"110;
%"TAP"
"1","(-3325,3650)","0","mstr_standard","I210";
;
CDS_LIB"mstr_standard"
BODY_TYPE"PLUMBING"
HDL_TAP"TRUE";
"B \NAC \NWC"2;
"S \NAC"
BN"13"109;
%"TAP"
"1","(-3325,3550)","0","mstr_standard","I211";
;
CDS_LIB"mstr_standard"
BODY_TYPE"PLUMBING"
HDL_TAP"TRUE";
"B \NAC \NWC"2;
"S \NAC"
BN"15"107;
%"TAP"
"1","(-3325,3450)","0","mstr_standard","I212";
;
CDS_LIB"mstr_standard"
BODY_TYPE"PLUMBING"
HDL_TAP"TRUE";
"B \NAC \NWC"2;
"S \NAC"
BN"16"106;
%"TAP"
"1","(-3325,3400)","0","mstr_standard","I213";
;
CDS_LIB"mstr_standard"
BODY_TYPE"PLUMBING"
HDL_TAP"TRUE";
"B \NAC \NWC"2;
"S \NAC"
BN"17"105;
%"TAP"
"1","(-3325,3350)","0","mstr_standard","I214";
;
CDS_LIB"mstr_standard"
BODY_TYPE"PLUMBING"
HDL_TAP"TRUE";
"B \NAC \NWC"2;
"S \NAC"
BN"18"104;
%"TAP"
"1","(-3325,3250)","0","mstr_standard","I215";
;
CDS_LIB"mstr_standard"
BODY_TYPE"PLUMBING"
HDL_TAP"TRUE";
"B \NAC \NWC"2;
"S \NAC"
BN"20"116;
%"TAP"
"1","(-3325,3300)","0","mstr_standard","I216";
;
CDS_LIB"mstr_standard"
BODY_TYPE"PLUMBING"
HDL_TAP"TRUE";
"B \NAC \NWC"2;
"S \NAC"
BN"19"120;
%"TAP"
"1","(-3325,3200)","0","mstr_standard","I217";
;
CDS_LIB"mstr_standard"
BODY_TYPE"PLUMBING"
HDL_TAP"TRUE";
"B \NAC \NWC"2;
"S \NAC"
BN"21"115;
%"TAP"
"1","(-3325,3100)","0","mstr_standard","I218";
;
CDS_LIB"mstr_standard"
BODY_TYPE"PLUMBING"
HDL_TAP"TRUE";
"B \NAC \NWC"2;
"S \NAC"
BN"23"111;
%"TAP"
"1","(-3325,3150)","0","mstr_standard","I219";
;
CDS_LIB"mstr_standard"
BODY_TYPE"PLUMBING"
HDL_TAP"TRUE";
"B \NAC \NWC"2;
"S \NAC"
BN"22"113;
%"TAP"
"1","(-3325,3000)","0","mstr_standard","I220";
;
CDS_LIB"mstr_standard"
BODY_TYPE"PLUMBING"
HDL_TAP"TRUE";
"B \NAC \NWC"2;
"S \NAC"
BN"24"90;
%"TAP"
"1","(-3325,2950)","0","mstr_standard","I221";
;
CDS_LIB"mstr_standard"
BODY_TYPE"PLUMBING"
HDL_TAP"TRUE";
"B \NAC \NWC"2;
"S \NAC"
BN"25"89;
%"TAP"
"1","(-3325,2850)","0","mstr_standard","I222";
;
CDS_LIB"mstr_standard"
BODY_TYPE"PLUMBING"
HDL_TAP"TRUE";
"B \NAC \NWC"2;
"S \NAC"
BN"27"87;
%"TAP"
"1","(-3325,2900)","0","mstr_standard","I223";
;
CDS_LIB"mstr_standard"
BODY_TYPE"PLUMBING"
HDL_TAP"TRUE";
"B \NAC \NWC"2;
"S \NAC"
BN"26"88;
%"TAP"
"1","(-3325,2750)","0","mstr_standard","I224";
;
CDS_LIB"mstr_standard"
BODY_TYPE"PLUMBING"
HDL_TAP"TRUE";
"B \NAC \NWC"2;
"S \NAC"
BN"29"85;
%"TAP"
"1","(-3325,2800)","0","mstr_standard","I225";
;
CDS_LIB"mstr_standard"
BODY_TYPE"PLUMBING"
HDL_TAP"TRUE";
"B \NAC \NWC"2;
"S \NAC"
BN"28"86;
%"TAP"
"1","(-3325,2700)","0","mstr_standard","I226";
;
CDS_LIB"mstr_standard"
BODY_TYPE"PLUMBING"
HDL_TAP"TRUE";
"B \NAC \NWC"2;
"S \NAC"
BN"30"97;
%"TAP"
"1","(-3325,2650)","0","mstr_standard","I227";
;
CDS_LIB"mstr_standard"
BODY_TYPE"PLUMBING"
HDL_TAP"TRUE";
"B \NAC \NWC"2;
"S \NAC"
BN"31"95;
%"TAP"
"1","(-3325,2500)","0","mstr_standard","I228";
;
CDS_LIB"mstr_standard"
BODY_TYPE"PLUMBING"
HDL_TAP"TRUE";
"B \NAC \NWC"3;
"S \NAC"
BN"1"101;
%"TAP"
"1","(-3325,2450)","0","mstr_standard","I229";
;
CDS_LIB"mstr_standard"
BODY_TYPE"PLUMBING"
HDL_TAP"TRUE";
"B \NAC \NWC"3;
"S \NAC"
BN"2"100;
%"TAP"
"1","(-3325,2550)","0","mstr_standard","I230";
;
CDS_LIB"mstr_standard"
BODY_TYPE"PLUMBING"
HDL_TAP"TRUE";
"B \NAC \NWC"3;
"S \NAC"
BN"0"102;
%"TAP"
"1","(-3325,2400)","0","mstr_standard","I231";
;
CDS_LIB"mstr_standard"
BODY_TYPE"PLUMBING"
HDL_TAP"TRUE";
"B \NAC \NWC"3;
"S \NAC"
BN"3"99;
%"TAP"
"1","(-3325,2350)","0","mstr_standard","I232";
;
CDS_LIB"mstr_standard"
BODY_TYPE"PLUMBING"
HDL_TAP"TRUE";
"B \NAC \NWC"3;
"S \NAC"
BN"4"98;
%"TAP"
"1","(-3325,2200)","0","mstr_standard","I233";
;
CDS_LIB"mstr_standard"
BODY_TYPE"PLUMBING"
HDL_TAP"TRUE";
"B \NAC \NWC"3;
"S \NAC"
BN"7"91;
%"TAP"
"1","(-3325,2300)","0","mstr_standard","I234";
;
CDS_LIB"mstr_standard"
BODY_TYPE"PLUMBING"
HDL_TAP"TRUE";
"B \NAC \NWC"3;
"S \NAC"
BN"5"96;
%"TAP"
"1","(-3325,2250)","0","mstr_standard","I235";
;
CDS_LIB"mstr_standard"
BODY_TYPE"PLUMBING"
HDL_TAP"TRUE";
"B \NAC \NWC"3;
"S \NAC"
BN"6"93;
%"TAP"
"1","(-3325,2050)","0","mstr_standard","I236";
;
CDS_LIB"mstr_standard"
BODY_TYPE"PLUMBING"
HDL_TAP"TRUE";
"B \NAC \NWC"4;
"S \NAC"
BN"1"92;
%"TAP"
"1","(-3325,2100)","0","mstr_standard","I237";
;
CDS_LIB"mstr_standard"
BODY_TYPE"PLUMBING"
HDL_TAP"TRUE";
"B \NAC \NWC"4;
"S \NAC"
BN"0"94;
%"TAP"
"1","(-3325,2000)","0","mstr_standard","I238";
;
CDS_LIB"mstr_standard"
BODY_TYPE"PLUMBING"
HDL_TAP"TRUE";
"B \NAC \NWC"4;
"S \NAC"
BN"2"84;
%"TAP"
"1","(-3325,1950)","0","mstr_standard","I239";
;
CDS_LIB"mstr_standard"
BODY_TYPE"PLUMBING"
HDL_TAP"TRUE";
"B \NAC \NWC"4;
"S \NAC"
BN"3"83;
%"TAP"
"1","(-3325,1800)","0","mstr_standard","I240";
;
CDS_LIB"mstr_standard"
BODY_TYPE"PLUMBING"
HDL_TAP"TRUE";
"B \NAC \NWC"4;
"S \NAC"
BN"6"80;
%"TAP"
"1","(-3325,1900)","0","mstr_standard","I241";
;
CDS_LIB"mstr_standard"
BODY_TYPE"PLUMBING"
HDL_TAP"TRUE";
"B \NAC \NWC"4;
"S \NAC"
BN"4"82;
%"TAP"
"1","(-3325,1850)","0","mstr_standard","I242";
;
CDS_LIB"mstr_standard"
BODY_TYPE"PLUMBING"
HDL_TAP"TRUE";
"B \NAC \NWC"4;
"S \NAC"
BN"5"81;
%"TAP"
"1","(-3325,1750)","0","mstr_standard","I243";
;
CDS_LIB"mstr_standard"
BODY_TYPE"PLUMBING"
HDL_TAP"TRUE";
"B \NAC \NWC"4;
"S \NAC"
BN"7"79;
%"TAP"
"1","(-5750,6150)","2","mstr_standard","I244";
;
CDS_LIB"mstr_standard"
BODY_TYPE"PLUMBING"
HDL_TAP"TRUE";
"B \NAC \NWC"5;
"S \NAC"
BN"0"78;
%"TAP"
"1","(-5750,6050)","2","mstr_standard","I245";
;
CDS_LIB"mstr_standard"
BODY_TYPE"PLUMBING"
HDL_TAP"TRUE";
"B \NAC \NWC"5;
"S \NAC"
BN"1"69;
%"TAP"
"1","(-5750,5950)","2","mstr_standard","I246";
;
CDS_LIB"mstr_standard"
BODY_TYPE"PLUMBING"
HDL_TAP"TRUE";
"B \NAC \NWC"5;
"S \NAC"
BN"2"67;
%"TAP"
"1","(-5750,5850)","2","mstr_standard","I247";
;
CDS_LIB"mstr_standard"
BODY_TYPE"PLUMBING"
HDL_TAP"TRUE";
"B \NAC \NWC"5;
"S \NAC"
BN"3"65;
%"TAP"
"1","(-5750,5650)","2","mstr_standard","I248";
;
CDS_LIB"mstr_standard"
BODY_TYPE"PLUMBING"
HDL_TAP"TRUE";
"B \NAC \NWC"5;
"S \NAC"
BN"5"61;
%"TAP"
"1","(-5750,5750)","2","mstr_standard","I249";
;
CDS_LIB"mstr_standard"
BODY_TYPE"PLUMBING"
HDL_TAP"TRUE";
"B \NAC \NWC"5;
"S \NAC"
BN"4"63;
%"TAP"
"1","(-5950,6100)","2","mstr_standard","I250";
;
CDS_LIB"mstr_standard"
BODY_TYPE"PLUMBING"
HDL_TAP"TRUE";
"B \NAC \NWC"6;
"S \NAC"
BN"0"75;
%"TAP"
"1","(-5950,6000)","2","mstr_standard","I251";
;
CDS_LIB"mstr_standard"
BODY_TYPE"PLUMBING"
HDL_TAP"TRUE";
"B \NAC \NWC"6;
"S \NAC"
BN"1"74;
%"TAP"
"1","(-5950,5900)","2","mstr_standard","I252";
;
CDS_LIB"mstr_standard"
BODY_TYPE"PLUMBING"
HDL_TAP"TRUE";
"B \NAC \NWC"6;
"S \NAC"
BN"2"73;
%"TAP"
"1","(-5950,5800)","2","mstr_standard","I253";
;
CDS_LIB"mstr_standard"
BODY_TYPE"PLUMBING"
HDL_TAP"TRUE";
"B \NAC \NWC"6;
"S \NAC"
BN"3"72;
%"TAP"
"1","(-5950,5700)","2","mstr_standard","I254";
;
CDS_LIB"mstr_standard"
BODY_TYPE"PLUMBING"
HDL_TAP"TRUE";
"B \NAC \NWC"6;
"S \NAC"
BN"4"71;
%"TAP"
"1","(-5750,5550)","2","mstr_standard","I255";
;
CDS_LIB"mstr_standard"
BODY_TYPE"PLUMBING"
HDL_TAP"TRUE";
"B \NAC \NWC"5;
"S \NAC"
BN"6"60;
%"TAP"
"1","(-5750,5450)","2","mstr_standard","I256";
;
CDS_LIB"mstr_standard"
BODY_TYPE"PLUMBING"
HDL_TAP"TRUE";
"B \NAC \NWC"5;
"S \NAC"
BN"7"59;
%"TAP"
"1","(-5750,5250)","2","mstr_standard","I257";
;
CDS_LIB"mstr_standard"
BODY_TYPE"PLUMBING"
HDL_TAP"TRUE";
"B \NAC \NWC"5;
"S \NAC"
BN"9"76;
%"TAP"
"1","(-5750,5350)","2","mstr_standard","I258";
;
CDS_LIB"mstr_standard"
BODY_TYPE"PLUMBING"
HDL_TAP"TRUE";
"B \NAC \NWC"5;
"S \NAC"
BN"8"77;
%"TAP"
"1","(-5950,5600)","2","mstr_standard","I259";
;
CDS_LIB"mstr_standard"
BODY_TYPE"PLUMBING"
HDL_TAP"TRUE";
"B \NAC \NWC"6;
"S \NAC"
BN"5"70;
%"TAP"
"1","(-5950,5500)","2","mstr_standard","I260";
;
CDS_LIB"mstr_standard"
BODY_TYPE"PLUMBING"
HDL_TAP"TRUE";
"B \NAC \NWC"6;
"S \NAC"
BN"6"68;
%"TAP"
"1","(-5950,5400)","2","mstr_standard","I261";
;
CDS_LIB"mstr_standard"
BODY_TYPE"PLUMBING"
HDL_TAP"TRUE";
"B \NAC \NWC"6;
"S \NAC"
BN"7"66;
%"TAP"
"1","(-5950,5300)","2","mstr_standard","I262";
;
CDS_LIB"mstr_standard"
BODY_TYPE"PLUMBING"
HDL_TAP"TRUE";
"B \NAC \NWC"6;
"S \NAC"
BN"8"64;
%"TAP"
"1","(-5950,5200)","2","mstr_standard","I263";
;
CDS_LIB"mstr_standard"
BODY_TYPE"PLUMBING"
HDL_TAP"TRUE";
"B \NAC \NWC"6;
"S \NAC"
BN"9"62;
%"TAP"
"1","(-5750,5000)","2","mstr_standard","I264";
;
CDS_LIB"mstr_standard"
BODY_TYPE"PLUMBING"
HDL_TAP"TRUE";
"B \NAC \NWC"8;
"S \NAC"
BN"1"40;
%"TAP"
"1","(-5750,5100)","2","mstr_standard","I265";
;
CDS_LIB"mstr_standard"
BODY_TYPE"PLUMBING"
HDL_TAP"TRUE";
"B \NAC \NWC"8;
"S \NAC"
BN"0"42;
%"TAP"
"1","(-5750,4900)","2","mstr_standard","I266";
;
CDS_LIB"mstr_standard"
BODY_TYPE"PLUMBING"
HDL_TAP"TRUE";
"B \NAC \NWC"8;
"S \NAC"
BN"2"57;
%"TAP"
"1","(-5750,4800)","2","mstr_standard","I267";
;
CDS_LIB"mstr_standard"
BODY_TYPE"PLUMBING"
HDL_TAP"TRUE";
"B \NAC \NWC"8;
"S \NAC"
BN"3"55;
%"TAP"
"1","(-5750,4700)","2","mstr_standard","I268";
;
CDS_LIB"mstr_standard"
BODY_TYPE"PLUMBING"
HDL_TAP"TRUE";
"B \NAC \NWC"8;
"S \NAC"
BN"4"53;
%"TAP"
"1","(-5950,5050)","2","mstr_standard","I269";
;
CDS_LIB"mstr_standard"
BODY_TYPE"PLUMBING"
HDL_TAP"TRUE";
"B \NAC \NWC"7;
"S \NAC"
BN"0"47;
%"TAP"
"1","(-5950,4950)","2","mstr_standard","I270";
;
CDS_LIB"mstr_standard"
BODY_TYPE"PLUMBING"
HDL_TAP"TRUE";
"B \NAC \NWC"7;
"S \NAC"
BN"1"46;
%"TAP"
"1","(-5950,4850)","2","mstr_standard","I271";
;
CDS_LIB"mstr_standard"
BODY_TYPE"PLUMBING"
HDL_TAP"TRUE";
"B \NAC \NWC"7;
"S \NAC"
BN"2"45;
%"TAP"
"1","(-5950,4750)","2","mstr_standard","I272";
;
CDS_LIB"mstr_standard"
BODY_TYPE"PLUMBING"
HDL_TAP"TRUE";
"B \NAC \NWC"7;
"S \NAC"
BN"3"44;
%"TAP"
"1","(-5950,4650)","2","mstr_standard","I273";
;
CDS_LIB"mstr_standard"
BODY_TYPE"PLUMBING"
HDL_TAP"TRUE";
"B \NAC \NWC"7;
"S \NAC"
BN"4"43;
%"TAP"
"1","(-5750,4500)","2","mstr_standard","I274";
;
CDS_LIB"mstr_standard"
BODY_TYPE"PLUMBING"
HDL_TAP"TRUE";
"B \NAC \NWC"8;
"S \NAC"
BN"6"50;
%"TAP"
"1","(-5750,4600)","2","mstr_standard","I275";
;
CDS_LIB"mstr_standard"
BODY_TYPE"PLUMBING"
HDL_TAP"TRUE";
"B \NAC \NWC"8;
"S \NAC"
BN"5"51;
%"TAP"
"1","(-5750,4400)","2","mstr_standard","I276";
;
CDS_LIB"mstr_standard"
BODY_TYPE"PLUMBING"
HDL_TAP"TRUE";
"B \NAC \NWC"8;
"S \NAC"
BN"7"49;
%"TAP"
"1","(-5750,4300)","2","mstr_standard","I277";
;
CDS_LIB"mstr_standard"
BODY_TYPE"PLUMBING"
HDL_TAP"TRUE";
"B \NAC \NWC"8;
"S \NAC"
BN"8"48;
%"TAP"
"1","(-5750,4200)","2","mstr_standard","I278";
;
CDS_LIB"mstr_standard"
BODY_TYPE"PLUMBING"
HDL_TAP"TRUE";
"B \NAC \NWC"8;
"S \NAC"
BN"9"39;
%"TAP"
"1","(-5950,4550)","2","mstr_standard","I279";
;
CDS_LIB"mstr_standard"
BODY_TYPE"PLUMBING"
HDL_TAP"TRUE";
"B \NAC \NWC"7;
"S \NAC"
BN"5"41;
%"TAP"
"1","(-5950,4450)","2","mstr_standard","I280";
;
CDS_LIB"mstr_standard"
BODY_TYPE"PLUMBING"
HDL_TAP"TRUE";
"B \NAC \NWC"7;
"S \NAC"
BN"6"58;
%"TAP"
"1","(-5950,4350)","2","mstr_standard","I281";
;
CDS_LIB"mstr_standard"
BODY_TYPE"PLUMBING"
HDL_TAP"TRUE";
"B \NAC \NWC"7;
"S \NAC"
BN"7"56;
%"TAP"
"1","(-5950,4150)","2","mstr_standard","I282";
;
CDS_LIB"mstr_standard"
BODY_TYPE"PLUMBING"
HDL_TAP"TRUE";
"B \NAC \NWC"7;
"S \NAC"
BN"9"52;
%"TAP"
"1","(-5950,4250)","2","mstr_standard","I283";
;
CDS_LIB"mstr_standard"
BODY_TYPE"PLUMBING"
HDL_TAP"TRUE";
"B \NAC \NWC"7;
"S \NAC"
BN"8"54;
%"TAP"
"1","(-5950,3950)","2","mstr_standard","I288";
;
CDS_LIB"mstr_standard"
BODY_TYPE"PLUMBING"
HDL_TAP"TRUE";
"B \NAC \NWC"9;
"S \NAC"
BN"1"36;
%"TAP"
"1","(-5950,4000)","2","mstr_standard","I289";
;
CDS_LIB"mstr_standard"
BODY_TYPE"PLUMBING"
HDL_TAP"TRUE";
"B \NAC \NWC"9;
"S \NAC"
BN"0"38;
%"TAP"
"1","(-5950,3900)","2","mstr_standard","I290";
;
CDS_LIB"mstr_standard"
BODY_TYPE"PLUMBING"
HDL_TAP"TRUE";
"B \NAC \NWC"9;
"S \NAC"
BN"2"34;
%"TAP"
"1","(-5950,3850)","2","mstr_standard","I291";
;
CDS_LIB"mstr_standard"
BODY_TYPE"PLUMBING"
HDL_TAP"TRUE";
"B \NAC \NWC"9;
"S \NAC"
BN"3"32;
%"TAP"
"1","(-5950,3800)","2","mstr_standard","I292";
;
CDS_LIB"mstr_standard"
BODY_TYPE"PLUMBING"
HDL_TAP"TRUE";
"B \NAC \NWC"9;
"S \NAC"
BN"4"30;
%"TAP"
"1","(-5950,3750)","2","mstr_standard","I293";
;
CDS_LIB"mstr_standard"
BODY_TYPE"PLUMBING"
HDL_TAP"TRUE";
"B \NAC \NWC"9;
"S \NAC"
BN"5"28;
%"TAP"
"1","(-5950,3700)","2","mstr_standard","I294";
;
CDS_LIB"mstr_standard"
BODY_TYPE"PLUMBING"
HDL_TAP"TRUE";
"B \NAC \NWC"9;
"S \NAC"
BN"6"26;
%"TAP"
"1","(-5950,3600)","2","mstr_standard","I295";
;
CDS_LIB"mstr_standard"
BODY_TYPE"PLUMBING"
HDL_TAP"TRUE";
"B \NAC \NWC"10;
"S \NAC"
BN"0"37;
%"TAP"
"1","(-5950,3500)","2","mstr_standard","I296";
;
CDS_LIB"mstr_standard"
BODY_TYPE"PLUMBING"
HDL_TAP"TRUE";
"B \NAC \NWC"10;
"S \NAC"
BN"2"33;
%"TAP"
"1","(-5950,3550)","2","mstr_standard","I297";
;
CDS_LIB"mstr_standard"
BODY_TYPE"PLUMBING"
HDL_TAP"TRUE";
"B \NAC \NWC"10;
"S \NAC"
BN"1"35;
%"TAP"
"1","(-5950,3450)","2","mstr_standard","I298";
;
CDS_LIB"mstr_standard"
BODY_TYPE"PLUMBING"
HDL_TAP"TRUE";
"B \NAC \NWC"10;
"S \NAC"
BN"3"31;
%"TAP"
"1","(-5950,3400)","2","mstr_standard","I299";
;
CDS_LIB"mstr_standard"
BODY_TYPE"PLUMBING"
HDL_TAP"TRUE";
"B \NAC \NWC"10;
"S \NAC"
BN"4"29;
%"TAP"
"1","(-5950,3350)","2","mstr_standard","I300";
;
CDS_LIB"mstr_standard"
BODY_TYPE"PLUMBING"
HDL_TAP"TRUE";
"B \NAC \NWC"10;
"S \NAC"
BN"5"27;
%"TAP"
"1","(-5950,3300)","2","mstr_standard","I301";
;
CDS_LIB"mstr_standard"
BODY_TYPE"PLUMBING"
HDL_TAP"TRUE";
"B \NAC \NWC"10;
"S \NAC"
BN"6"25;
%"Q_RES"
"1","(-6625,2300)","0","pure_quanta","I314";
;
LOCATION"R505"
$SEC"1"
CDS_SEC"1"
PACK_TYPE"0402LF"
TOLERANCE"1%"
VALUE"15"
MATERIAL"CHIP"
WATTAGE"1/16W"
CDS_LIB"pure_quanta"
PART_NUMBER"CS01502FB03";
"B"
$PN"2"12;
"A"
$PN"1"11;
END.
